# T6G (Grand Teton) — schematic netlist excerpt (pin names and nets, part order shuffled) for the footprints in the layout excerpt that follows; sources: Cadence DE-HDL packaged netlist, KiCad conversion of 04192023_DAF0TMB3IC0_F0TG_MB_C_brd_V02_OCP.brd

PC6529  Q_CAP  22UF 4V 20% X6S  pkg C0805  page 361 : A = P1V8_CPU1_RT_1D ; B = GND
R3320  Q_RES  4.7K 5% CHIP  pkg 0402LF  page 127 : A = P3V3_AUX ; B = GPU_FPGA_READY_N
R1064  Q_RES  200 1% CHIP  pkg 0201LF  page 298 : A = RT_CPU0_P2_SCAN_MODE ; B = GND
C441  Q_CAP  1UF 4V 20% X6S  pkg 0201  page 356 : A = P1V8_CPU1_RT3_1A_1D ; B = GND

(kicad_pcb
	(version 20260206)
	(generator "pcbnew")
	(generator_version "10.0")
	(general
		(thickness 1.6)
		(legacy_teardrops no)
	)
	(paper "A4")
	(title_block
		(title "04192023_DAF0TMB3IC0_F0TG_MB_C_brd_V02_OCP.brd")
		(comment 1 "Grand Teton / footprints 5982-5985 of 8354")
	)
	(layers
		(0 "F.Cu" signal "TOP")
		(4 "In1.Cu" signal "GND")
		(6 "In2.Cu" signal "IN1")
		(8 "In3.Cu" signal "GND1")
		(10 "In4.Cu" signal "IN2")
		(12 "In5.Cu" signal "GND2")
		(14 "In6.Cu" signal "IN3")
		(16 "In7.Cu" signal "GND3")
		(18 "In8.Cu" signal "VCC")
		(20 "In9.Cu" signal "VCC1")
		(22 "In10.Cu" signal "GND4")
		(24 "In11.Cu" signal "IN4")
		(26 "In12.Cu" signal "GND5")
		(28 "In13.Cu" signal "IN5")
		(30 "In14.Cu" signal "GND6")
		(32 "In15.Cu" signal "IN6")
		(34 "In16.Cu" signal "GND7")
		(2 "B.Cu" signal "BOTTOM")
		(9 "F.Adhes" user "F.Adhesive")
		(11 "B.Adhes" user "B.Adhesive")
		(13 "F.Paste" user "Package Geometry/Pastemask Top")
		(15 "B.Paste" user "Package Geometry/Pastemask Bottom")
		(5 "F.SilkS" user "Ref Des/Silkscreen Top")
		(7 "B.SilkS" user "Ref Des/Silkscreen Bottom")
		(1 "F.Mask" user "Board Geometry/Soldermask Top")
		(3 "B.Mask" user "Board Geometry/Soldermask Bottom")
		(17 "Dwgs.User" user "User.Drawings")
		(19 "Cmts.User" user "User.Comments")
		(21 "Eco1.User" user "User.Eco1")
		(23 "Eco2.User" user "User.Eco2")
		(25 "Edge.Cuts" user "Board Geometry/Outline")
		(27 "Margin" user)
		(31 "F.CrtYd" user "Package Geometry/Place Bound Top")
		(29 "B.CrtYd" user "Package Geometry/Place Bound Bottom")
		(35 "F.Fab" user "Ref Des/Assembly Top")
		(33 "B.Fab" user "Ref Des/Assembly Bottom")
	)
	(footprint ""
		(layer "B.Cu")
		(at 230.891842 -315.95568 -90)
		(property "Reference" "PC6529"
			(at 0 0 90)
			(layer "B.SilkS")
			(hide yes)
			(effects
				(font
					(size 1.27 1.27)
				)
				(justify mirror)
			)
		)
		(property "Value" ""
			(at 0 0 90)
			(layer "B.Fab")
			(effects
				(font
					(size 1.27 1.27)
				)
				(justify mirror)
			)
		)
		(duplicate_pad_numbers_are_jumpers no)
		(fp_line
			(start -1.524 0.762)
			(end 1.524 0.762)
			(stroke
				(width 0.1524)
				(type default)
			)
			(layer "B.SilkS")
		)
		(fp_line
			(start 1.524 0.762)
			(end 1.524 -0.762)
			(stroke
				(width 0.1524)
				(type default)
			)
			(layer "B.SilkS")
		)
		(fp_line
			(start -1.524 -0.762)
			(end -1.524 0.762)
			(stroke
				(width 0.1524)
				(type default)
			)
			(layer "B.SilkS")
		)
		(fp_line
			(start 1.524 -0.762)
			(end -1.524 -0.762)
			(stroke
				(width 0.1524)
				(type default)
			)
			(layer "B.SilkS")
		)
		(fp_line
			(start -1.1049 0.724916)
			(end -1.1049 -0.724916)
			(stroke
				(width 0.1)
				(type default)
			)
			(layer "B.Fab")
		)
		(fp_line
			(start 1.1049 0.724916)
			(end -1.1049 0.724916)
			(stroke
				(width 0.1)
				(type default)
			)
			(layer "B.Fab")
		)
		(fp_line
			(start -1.1049 -0.724916)
			(end 1.1049 -0.724916)
			(stroke
				(width 0.1)
				(type default)
			)
			(layer "B.Fab")
		)
		(fp_line
			(start 1.1049 -0.724916)
			(end 1.1049 0.724916)
			(stroke
				(width 0.1)
				(type default)
			)
			(layer "B.Fab")
		)
		(pad "1" smd rect
			(at 0.889 0 270)
			(size 1.016 1.27)
			(layers "B.Cu" "B.Mask" "B.Paste")
			(net "P1V8_CPU1_RT_1D")
		)
		(pad "2" smd rect
			(at -0.889 0 270)
			(size 1.016 1.27)
			(layers "B.Cu" "B.Mask" "B.Paste")
			(net "GND")
		)
	)
	(footprint ""
		(layer "B.Cu")
		(at 46.434502 -422.527984 90)
		(property "Reference" "R3320"
			(at 0 0 90)
			(layer "B.SilkS")
			(hide yes)
			(effects
				(font
					(size 1.27 1.27)
				)
				(justify mirror)
			)
		)
		(property "Value" ""
			(at 0 0 90)
			(layer "B.Fab")
			(effects
				(font
					(size 1.27 1.27)
				)
				(justify mirror)
			)
		)
		(duplicate_pad_numbers_are_jumpers no)
		(fp_line
			(start 0.7874 -0.4064)
			(end -0.7874 -0.4064)
			(stroke
				(width 0.1524)
				(type default)
			)
			(layer "B.SilkS")
		)
		(fp_line
			(start -0.7874 -0.4064)
			(end -0.7874 0.4064)
			(stroke
				(width 0.1524)
				(type default)
			)
			(layer "B.SilkS")
		)
		(fp_line
			(start 0.7874 0.4064)
			(end 0.7874 -0.4064)
			(stroke
				(width 0.1524)
				(type default)
			)
			(layer "B.SilkS")
		)
		(fp_line
			(start -0.7874 0.4064)
			(end 0.7874 0.4064)
			(stroke
				(width 0.1524)
				(type default)
			)
			(layer "B.SilkS")
		)
		(fp_line
			(start 0.67945 -0.305054)
			(end 0.12065 -0.305054)
			(stroke
				(width 0.1)
				(type default)
			)
			(layer "B.Fab")
		)
		(fp_line
			(start 0.12065 -0.305054)
			(end 0.12065 -0.2794)
			(stroke
				(width 0.1)
				(type default)
			)
			(layer "B.Fab")
		)
		(fp_line
			(start -0.12065 -0.3048)
			(end -0.67945 -0.3048)
			(stroke
				(width 0.1)
				(type default)
			)
			(layer "B.Fab")
		)
		(fp_line
			(start -0.67945 -0.3048)
			(end -0.67945 0.3048)
			(stroke
				(width 0.1)
				(type default)
			)
			(layer "B.Fab")
		)
		(fp_line
			(start 0.12065 -0.2794)
			(end -0.12065 -0.2794)
			(stroke
				(width 0.1)
				(type default)
			)
			(layer "B.Fab")
		)
		(fp_line
			(start -0.12065 -0.2794)
			(end -0.12065 -0.3048)
			(stroke
				(width 0.1)
				(type default)
			)
			(layer "B.Fab")
		)
		(fp_line
			(start 0.12065 0.2794)
			(end 0.12065 0.3048)
			(stroke
				(width 0.1)
				(type default)
			)
			(layer "B.Fab")
		)
		(fp_line
			(start -0.120396 0.2794)
			(end 0.12065 0.2794)
			(stroke
				(width 0.1)
				(type default)
			)
			(layer "B.Fab")
		)
		(fp_line
			(start 0.67945 0.3048)
			(end 0.67945 -0.305054)
			(stroke
				(width 0.1)
				(type default)
			)
			(layer "B.Fab")
		)
		(fp_line
			(start 0.12065 0.3048)
			(end 0.67945 0.3048)
			(stroke
				(width 0.1)
				(type default)
			)
			(layer "B.Fab")
		)
		(fp_line
			(start -0.120396 0.3048)
			(end -0.120396 0.2794)
			(stroke
				(width 0.1)
				(type default)
			)
			(layer "B.Fab")
		)
		(fp_line
			(start -0.67945 0.3048)
			(end -0.120396 0.3048)
			(stroke
				(width 0.1)
				(type default)
			)
			(layer "B.Fab")
		)
		(pad "1" smd circle
			(at 0.40005 0 270)
			(size 0 0)
			(layers "B.Cu" "B.Mask" "B.Paste")
			(net "P3V3_AUX")
		)
		(pad "2" smd circle
			(at -0.40005 0 270)
			(size 0 0)
			(layers "B.Cu" "B.Mask" "B.Paste")
			(net "GPU_FPGA_READY_N")
		)
	)
	(footprint ""
		(layer "B.Cu")
		(at 125.278388 -386.766562 90)
		(property "Reference" "C441"
			(at 0 0 90)
			(layer "B.SilkS")
			(hide yes)
			(effects
				(font
					(size 1.27 1.27)
				)
				(justify mirror)
			)
		)
		(property "Value" ""
			(at 0 0 90)
			(layer "B.Fab")
			(effects
				(font
					(size 1.27 1.27)
				)
				(justify mirror)
			)
		)
		(duplicate_pad_numbers_are_jumpers no)
		(fp_line
			(start 0.299974 -0.150114)
			(end -0.299974 -0.150114)
			(stroke
				(width 0.1)
				(type default)
			)
			(layer "B.Fab")
		)
		(fp_line
			(start -0.299974 -0.150114)
			(end -0.299974 0.150114)
			(stroke
				(width 0.1)
				(type default)
			)
			(layer "B.Fab")
		)
		(fp_line
			(start 0.299974 0.150114)
			(end 0.299974 -0.150114)
			(stroke
				(width 0.1)
				(type default)
			)
			(layer "B.Fab")
		)
		(fp_line
			(start -0.299974 0.150114)
			(end 0.299974 0.150114)
			(stroke
				(width 0.1)
				(type default)
			)
			(layer "B.Fab")
		)
		(pad "1" smd rect
			(at 0.2667 0 270)
			(size 0.3048 0.381)
			(layers "B.Cu" "B.Mask" "B.Paste")
			(net "P1V8_CPU1_RT3_1A_1D")
		)
		(pad "2" smd rect
			(at -0.2667 0 270)
			(size 0.3048 0.381)
			(layers "B.Cu" "B.Mask" "B.Paste")
			(net "GND")
		)
	)
	(footprint ""
		(layer "B.Cu")
		(at 398.893538 -392.1252 180)
		(property "Reference" "R1064"
			(at 0 0 0)
			(layer "B.SilkS")
			(hide yes)
			(effects
				(font
					(size 1.27 1.27)
				)
				(justify mirror)
			)
		)
		(property "Value" ""
			(at 0 0 0)
			(layer "B.Fab")
			(effects
				(font
					(size 1.27 1.27)
				)
				(justify mirror)
			)
		)
		(duplicate_pad_numbers_are_jumpers no)
		(fp_line
			(start 0.32512 0.175006)
			(end 0.32512 -0.175006)
			(stroke
				(width 0.1)
				(type default)
			)
			(layer "B.Fab")
		)
		(fp_line
			(start 0.32512 -0.175006)
			(end -0.32512 -0.175006)
			(stroke
				(width 0.1)
				(type default)
			)
			(layer "B.Fab")
		)
		(fp_line
			(start -0.32512 0.175006)
			(end 0.32512 0.175006)
			(stroke
				(width 0.1)
				(type default)
			)
			(layer "B.Fab")
		)
		(fp_line
			(start -0.32512 -0.175006)
			(end -0.32512 0.175006)
			(stroke
				(width 0.1)
				(type default)
			)
			(layer "B.Fab")
		)
		(pad "1" smd rect
			(at 0.2667 0)
			(size 0.3048 0.381)
			(layers "B.Cu" "B.Mask" "B.Paste")
			(net "RT_CPU0_P2_SCAN_MODE")
		)
		(pad "2" smd rect
			(at -0.2667 0 180)
			(size 0.3048 0.381)
			(layers "B.Cu" "B.Mask" "B.Paste")
			(net "GND")
		)
	)
)
